(kicad_pcb
	(version 20260206)
	(generator "pcbnew")
	(generator_version "10.0")
	(general
		(thickness 1.6)
		(legacy_teardrops no)
	)
	(paper "A4")
	(title_block
		(title "panther-plus-userver — 13130-1b_20150205.brd")
		(comment 1 "Honey Badger (Wiwynn) / footprint 1214 of 1509 (DIMM3), pads 142-148 of 210")
	)
	(layers
		(0 "F.Cu" signal "TOP")
		(4 "In1.Cu" signal "L2")
		(6 "In2.Cu" signal "L3")
		(8 "In3.Cu" signal "L4")
		(10 "In4.Cu" signal "L5")
		(12 "In5.Cu" signal "L6")
		(14 "In6.Cu" signal "L7")
		(16 "In7.Cu" signal "L8")
		(18 "In8.Cu" signal "L9")
		(20 "In9.Cu" signal "L10")
		(22 "In10.Cu" signal "L11")
		(2 "B.Cu" signal "BOTTOM")
		(9 "F.Adhes" user "F.Adhesive")
		(11 "B.Adhes" user "B.Adhesive")
		(13 "F.Paste" user "Package Geometry/Pastemask Top")
		(15 "B.Paste" user "Package Geometry/Pastemask Bottom")
		(5 "F.SilkS" user "Ref Des/Silkscreen Top")
		(7 "B.SilkS" user "Ref Des/Silkscreen Bottom")
		(1 "F.Mask" user "Board Geometry/Soldermask Top")
		(3 "B.Mask" user "Board Geometry/Soldermask Bottom")
		(17 "Dwgs.User" user "User.Drawings")
		(19 "Cmts.User" user "User.Comments")
		(21 "Eco1.User" user "User.Eco1")
		(23 "Eco2.User" user "User.Eco2")
		(25 "Edge.Cuts" user "Board Geometry/Outline")
		(27 "Margin" user)
		(31 "F.CrtYd" user "Package Geometry/Place Bound Top")
		(29 "B.CrtYd" user "Package Geometry/Place Bound Bottom")
		(35 "F.Fab" user "Ref Des/Assembly Top")
		(33 "B.Fab" user "Ref Des/Assembly Bottom")
	)
	(footprint ""
		(layer "B.Cu")
		(at 159.999934 -5.790692)
		(property "Reference" "DIMM3"
			(at 0 0 0)
			(layer "B.SilkS")
			(hide yes)
			(effects
				(font
					(size 1.27 1.27)
				)
				(justify mirror)
			)
		)
		(property "Value" "DDR3-204P-142-COLAY-1-GP-U"
			(at 41.312338 -16.676878 0)
			(unlocked yes)
			(layer "B.Fab")
			(hide yes)
			(effects
				(font
					(size 1.016 1.016)
					(thickness 0.1524)
				)
				(justify mirror)
			)
		)
		(property "Device Type" "AS0A626-J8R6-7H-COLAY-1"
			(at 41.312338 -18.200878 0)
			(unlocked yes)
			(layer "B.Fab")
			(hide yes)
			(effects
				(font
					(size 1.016 1.016)
					(thickness 0.1524)
				)
				(justify mirror)
			)
		)
		(duplicate_pad_numbers_are_jumpers no)
		(pad "140" smd custom
			(at 12.450064 4.100068 180)
			(size 0.1143 0.1143)
			(layers "B.Cu" "B.Mask" "B.Paste")
			(net "GND")
			(options
				(clearance outline)
				(anchor circle)
			)
			(primitives
				(gr_poly
					(pts
						(xy 0 -0.9017) (xy -0.03175 -0.89916) (xy -0.0635 -0.889) (xy -0.09144 -0.87376) (xy -0.11684 -0.85344)
						(xy -0.13716 -0.82804) (xy -0.1524 -0.8001) (xy -0.16256 -0.76835) (xy -0.1651 -0.7366) (xy -0.1651 -0.11938)
						(xy -0.17272 -0.11176) (xy -0.19812 -0.0762) (xy -0.2032 -0.06604) (xy -0.20701 -0.05715) (xy -0.21209 -0.04699)
						(xy -0.2159 -0.03683) (xy -0.21844 -0.02667) (xy -0.22225 -0.01524) (xy -0.22352 -0.00508) (xy -0.22606 0.00508)
						(xy -0.22733 0.01651) (xy -0.22733 0.02667) (xy -0.2286 0.0381) (xy -0.22733 0.04953) (xy -0.22733 0.05969)
						(xy -0.22606 0.07112) (xy -0.22352 0.08128) (xy -0.22225 0.09144) (xy -0.21844 0.10287) (xy -0.2159 0.11303)
						(xy -0.21209 0.12319) (xy -0.20701 0.13335) (xy -0.2032 0.14224) (xy -0.19812 0.1524) (xy -0.17272 0.18796)
						(xy -0.1651 0.19558) (xy -0.1651 0.7366) (xy -0.16256 0.76835) (xy -0.1524 0.8001) (xy -0.13716 0.82804)
						(xy -0.11684 0.85344) (xy -0.09144 0.87376) (xy -0.0635 0.889) (xy -0.03175 0.89916) (xy 0 0.9017)
						(xy 0.03175 0.89916) (xy 0.0635 0.889) (xy 0.09144 0.87376) (xy 0.11684 0.85344) (xy 0.13716 0.82804)
						(xy 0.1524 0.8001) (xy 0.16256 0.76835) (xy 0.1651 0.7366) (xy 0.1651 0.19685) (xy 0.17272 0.18923)
						(xy 0.17907 0.18034) (xy 0.18669 0.17145) (xy 0.19177 0.16256) (xy 0.19812 0.15367) (xy 0.20828 0.13335)
						(xy 0.21971 0.10287) (xy 0.22225 0.09271) (xy 0.22479 0.08128) (xy 0.22606 0.07112) (xy 0.2286 0.05969)
						(xy 0.2286 0.01651) (xy 0.22606 0.00508) (xy 0.22479 -0.00508) (xy 0.22225 -0.01651) (xy 0.21971 -0.02667)
						(xy 0.20828 -0.05715) (xy 0.19812 -0.07747) (xy 0.19177 -0.08636) (xy 0.18669 -0.09525) (xy 0.17907 -0.10414)
						(xy 0.17272 -0.11303) (xy 0.1651 -0.12065) (xy 0.1651 -0.7366) (xy 0.16256 -0.76835) (xy 0.1524 -0.8001)
						(xy 0.13716 -0.82804) (xy 0.11684 -0.85344) (xy 0.09144 -0.87376) (xy 0.0635 -0.889) (xy 0.03175 -0.89916)
					)
					(width 0)
					(fill yes)
				)
			)
		)
		(pad "141" smd custom
			(at 12.750038 -4.100068 180)
			(size 0.1143 0.1143)
			(layers "B.Cu" "B.Mask" "B.Paste")
			(net "M_B_DQS_DP4")
			(options
				(clearance outline)
				(anchor circle)
			)
			(primitives
				(gr_poly
					(pts
						(xy 0 -0.9017) (xy -0.03175 -0.89916) (xy -0.0635 -0.889) (xy -0.09144 -0.87376) (xy -0.11684 -0.85344)
						(xy -0.13716 -0.82804) (xy -0.1524 -0.8001) (xy -0.16256 -0.76835) (xy -0.1651 -0.7366) (xy -0.1651 -0.44958)
						(xy -0.17272 -0.44196) (xy -0.19812 -0.4064) (xy -0.2032 -0.39624) (xy -0.20701 -0.38735) (xy -0.21209 -0.37719)
						(xy -0.2159 -0.36703) (xy -0.21844 -0.35687) (xy -0.22225 -0.34544) (xy -0.22352 -0.33528) (xy -0.22606 -0.32512)
						(xy -0.22733 -0.31369) (xy -0.22733 -0.30353) (xy -0.2286 -0.2921) (xy -0.22733 -0.28067) (xy -0.22733 -0.27051)
						(xy -0.22606 -0.25908) (xy -0.22352 -0.24892) (xy -0.22225 -0.23876) (xy -0.21844 -0.22733) (xy -0.2159 -0.21717)
						(xy -0.21209 -0.20701) (xy -0.20701 -0.19685) (xy -0.2032 -0.18796) (xy -0.19812 -0.1778) (xy -0.17272 -0.14224)
						(xy -0.1651 -0.13462) (xy -0.1651 0.7366) (xy -0.16256 0.76835) (xy -0.1524 0.8001) (xy -0.13716 0.82804)
						(xy -0.11684 0.85344) (xy -0.09144 0.87376) (xy -0.0635 0.889) (xy -0.03175 0.89916) (xy 0 0.9017)
						(xy 0.03175 0.89916) (xy 0.0635 0.889) (xy 0.09144 0.87376) (xy 0.11684 0.85344) (xy 0.13716 0.82804)
						(xy 0.1524 0.8001) (xy 0.16256 0.76835) (xy 0.1651 0.7366) (xy 0.1651 -0.13462) (xy 0.17272 -0.14224)
						(xy 0.19812 -0.1778) (xy 0.2032 -0.18796) (xy 0.20701 -0.19685) (xy 0.21209 -0.20701) (xy 0.2159 -0.21717)
						(xy 0.21844 -0.22733) (xy 0.22225 -0.23876) (xy 0.22352 -0.24892) (xy 0.22606 -0.25908) (xy 0.22733 -0.27051)
						(xy 0.22733 -0.28067) (xy 0.2286 -0.2921) (xy 0.22733 -0.30353) (xy 0.22733 -0.31369) (xy 0.22606 -0.32512)
						(xy 0.22352 -0.33528) (xy 0.22225 -0.34544) (xy 0.21844 -0.35687) (xy 0.2159 -0.36703) (xy 0.21209 -0.37719)
						(xy 0.20701 -0.38735) (xy 0.2032 -0.39624) (xy 0.19812 -0.4064) (xy 0.17272 -0.44196) (xy 0.1651 -0.44958)
						(xy 0.1651 -0.7366) (xy 0.16256 -0.76835) (xy 0.1524 -0.8001) (xy 0.13716 -0.82804) (xy 0.11684 -0.85344)
						(xy 0.09144 -0.87376) (xy 0.0635 -0.889) (xy 0.03175 -0.89916)
					)
					(width 0)
					(fill yes)
				)
			)
		)
		(pad "142" smd custom
			(at 13.050012 4.100068 180)
			(size 0.1143 0.1143)
			(layers "B.Cu" "B.Mask" "B.Paste")
			(net "M_B_DQ38")
			(options
				(clearance outline)
				(anchor circle)
			)
			(primitives
				(gr_poly
					(pts
						(xy 0 -0.9017) (xy -0.03175 -0.89916) (xy -0.0635 -0.889) (xy -0.09144 -0.87376) (xy -0.11684 -0.85344)
						(xy -0.13716 -0.82804) (xy -0.1524 -0.8001) (xy -0.16256 -0.76835) (xy -0.1651 -0.7366) (xy -0.1651 0.13462)
						(xy -0.17272 0.14224) (xy -0.19812 0.1778) (xy -0.2032 0.18796) (xy -0.20701 0.19685) (xy -0.21209 0.20701)
						(xy -0.2159 0.21717) (xy -0.21844 0.22733) (xy -0.22225 0.23876) (xy -0.22352 0.24892) (xy -0.22606 0.25908)
						(xy -0.22733 0.27051) (xy -0.22733 0.28067) (xy -0.2286 0.2921) (xy -0.22733 0.30353) (xy -0.22733 0.31369)
						(xy -0.22606 0.32512) (xy -0.22352 0.33528) (xy -0.22225 0.34544) (xy -0.21844 0.35687) (xy -0.2159 0.36703)
						(xy -0.21209 0.37719) (xy -0.20701 0.38735) (xy -0.2032 0.39624) (xy -0.19812 0.4064) (xy -0.17272 0.44196)
						(xy -0.1651 0.44958) (xy -0.1651 0.7366) (xy -0.16256 0.76835) (xy -0.1524 0.8001) (xy -0.13716 0.82804)
						(xy -0.11684 0.85344) (xy -0.09144 0.87376) (xy -0.0635 0.889) (xy -0.03175 0.89916) (xy 0 0.9017)
						(xy 0.03175 0.89916) (xy 0.0635 0.889) (xy 0.09144 0.87376) (xy 0.11684 0.85344) (xy 0.13716 0.82804)
						(xy 0.1524 0.8001) (xy 0.16256 0.76835) (xy 0.1651 0.7366) (xy 0.1651 0.44958) (xy 0.17272 0.44196)
						(xy 0.19812 0.4064) (xy 0.2032 0.39624) (xy 0.20701 0.38735) (xy 0.21209 0.37719) (xy 0.2159 0.36703)
						(xy 0.21844 0.35687) (xy 0.22225 0.34544) (xy 0.22352 0.33528) (xy 0.22606 0.32512) (xy 0.22733 0.31369)
						(xy 0.22733 0.30353) (xy 0.2286 0.2921) (xy 0.22733 0.28067) (xy 0.22733 0.27051) (xy 0.22606 0.25908)
						(xy 0.22352 0.24892) (xy 0.22225 0.23876) (xy 0.21844 0.22733) (xy 0.2159 0.21717) (xy 0.21209 0.20701)
						(xy 0.20701 0.19685) (xy 0.2032 0.18796) (xy 0.19812 0.1778) (xy 0.17272 0.14224) (xy 0.1651 0.13462)
						(xy 0.1651 -0.7366) (xy 0.16256 -0.76835) (xy 0.1524 -0.8001) (xy 0.13716 -0.82804) (xy 0.11684 -0.85344)
						(xy 0.09144 -0.87376) (xy 0.0635 -0.889) (xy 0.03175 -0.89916)
					)
					(width 0)
					(fill yes)
				)
			)
		)
		(pad "143" smd custom
			(at 13.349986 -4.100068 180)
			(size 0.1143 0.1143)
			(layers "B.Cu" "B.Mask" "B.Paste")
			(net "GND")
			(options
				(clearance outline)
				(anchor circle)
			)
			(primitives
				(gr_poly
					(pts
						(xy 0 -0.9017) (xy -0.03175 -0.89916) (xy -0.0635 -0.889) (xy -0.09144 -0.87376) (xy -0.11684 -0.85344)
						(xy -0.13716 -0.82804) (xy -0.1524 -0.8001) (xy -0.16256 -0.76835) (xy -0.1651 -0.7366) (xy -0.1651 -0.19685)
						(xy -0.17272 -0.18923) (xy -0.17907 -0.18034) (xy -0.18669 -0.17145) (xy -0.19177 -0.16256) (xy -0.19812 -0.15367)
						(xy -0.20828 -0.13335) (xy -0.21971 -0.10287) (xy -0.22225 -0.09271) (xy -0.22479 -0.08128) (xy -0.22606 -0.07112)
						(xy -0.2286 -0.05969) (xy -0.2286 -0.01651) (xy -0.22606 -0.00508) (xy -0.22479 0.00508) (xy -0.22225 0.01651)
						(xy -0.21971 0.02667) (xy -0.20828 0.05715) (xy -0.19812 0.07747) (xy -0.19177 0.08636) (xy -0.18669 0.09525)
						(xy -0.17907 0.10414) (xy -0.17272 0.11303) (xy -0.1651 0.12065) (xy -0.1651 0.7366) (xy -0.16256 0.76835)
						(xy -0.1524 0.8001) (xy -0.13716 0.82804) (xy -0.11684 0.85344) (xy -0.09144 0.87376) (xy -0.0635 0.889)
						(xy -0.03175 0.89916) (xy 0 0.9017) (xy 0.03175 0.89916) (xy 0.0635 0.889) (xy 0.09144 0.87376)
						(xy 0.11684 0.85344) (xy 0.13716 0.82804) (xy 0.1524 0.8001) (xy 0.16256 0.76835) (xy 0.1651 0.7366)
						(xy 0.1651 0.11938) (xy 0.17272 0.11176) (xy 0.19812 0.0762) (xy 0.2032 0.06604) (xy 0.20701 0.05715)
						(xy 0.21209 0.04699) (xy 0.2159 0.03683) (xy 0.21844 0.02667) (xy 0.22225 0.01524) (xy 0.22352 0.00508)
						(xy 0.22606 -0.00508) (xy 0.22733 -0.01651) (xy 0.22733 -0.02667) (xy 0.2286 -0.0381) (xy 0.22733 -0.04953)
						(xy 0.22733 -0.05969) (xy 0.22606 -0.07112) (xy 0.22352 -0.08128) (xy 0.22225 -0.09144) (xy 0.21844 -0.10287)
						(xy 0.2159 -0.11303) (xy 0.21209 -0.12319) (xy 0.20701 -0.13335) (xy 0.2032 -0.14224) (xy 0.19812 -0.1524)
						(xy 0.17272 -0.18796) (xy 0.1651 -0.19558) (xy 0.1651 -0.7366) (xy 0.16256 -0.76835) (xy 0.1524 -0.8001)
						(xy 0.13716 -0.82804) (xy 0.11684 -0.85344) (xy 0.09144 -0.87376) (xy 0.0635 -0.889) (xy 0.03175 -0.89916)
					)
					(width 0)
					(fill yes)
				)
			)
		)
		(pad "144" smd custom
			(at 13.64996 4.100068 180)
			(size 0.1143 0.1143)
			(layers "B.Cu" "B.Mask" "B.Paste")
			(net "M_B_DQ39")
			(options
				(clearance outline)
				(anchor circle)
			)
			(primitives
				(gr_poly
					(pts
						(xy 0 -0.9017) (xy -0.03175 -0.89916) (xy -0.0635 -0.889) (xy -0.09144 -0.87376) (xy -0.11684 -0.85344)
						(xy -0.13716 -0.82804) (xy -0.1524 -0.8001) (xy -0.16256 -0.76835) (xy -0.1651 -0.7366) (xy -0.1651 -0.11938)
						(xy -0.17272 -0.11176) (xy -0.19812 -0.0762) (xy -0.2032 -0.06604) (xy -0.20701 -0.05715) (xy -0.21209 -0.04699)
						(xy -0.2159 -0.03683) (xy -0.21844 -0.02667) (xy -0.22225 -0.01524) (xy -0.22352 -0.00508) (xy -0.22606 0.00508)
						(xy -0.22733 0.01651) (xy -0.22733 0.02667) (xy -0.2286 0.0381) (xy -0.22733 0.04953) (xy -0.22733 0.05969)
						(xy -0.22606 0.07112) (xy -0.22352 0.08128) (xy -0.22225 0.09144) (xy -0.21844 0.10287) (xy -0.2159 0.11303)
						(xy -0.21209 0.12319) (xy -0.20701 0.13335) (xy -0.2032 0.14224) (xy -0.19812 0.1524) (xy -0.17272 0.18796)
						(xy -0.1651 0.19558) (xy -0.1651 0.7366) (xy -0.16256 0.76835) (xy -0.1524 0.8001) (xy -0.13716 0.82804)
						(xy -0.11684 0.85344) (xy -0.09144 0.87376) (xy -0.0635 0.889) (xy -0.03175 0.89916) (xy 0 0.9017)
						(xy 0.03175 0.89916) (xy 0.0635 0.889) (xy 0.09144 0.87376) (xy 0.11684 0.85344) (xy 0.13716 0.82804)
						(xy 0.1524 0.8001) (xy 0.16256 0.76835) (xy 0.1651 0.7366) (xy 0.1651 0.19685) (xy 0.17272 0.18923)
						(xy 0.17907 0.18034) (xy 0.18669 0.17145) (xy 0.19177 0.16256) (xy 0.19812 0.15367) (xy 0.20828 0.13335)
						(xy 0.21971 0.10287) (xy 0.22225 0.09271) (xy 0.22479 0.08128) (xy 0.22606 0.07112) (xy 0.2286 0.05969)
						(xy 0.2286 0.01651) (xy 0.22606 0.00508) (xy 0.22479 -0.00508) (xy 0.22225 -0.01651) (xy 0.21971 -0.02667)
						(xy 0.20828 -0.05715) (xy 0.19812 -0.07747) (xy 0.19177 -0.08636) (xy 0.18669 -0.09525) (xy 0.17907 -0.10414)
						(xy 0.17272 -0.11303) (xy 0.1651 -0.12065) (xy 0.1651 -0.7366) (xy 0.16256 -0.76835) (xy 0.1524 -0.8001)
						(xy 0.13716 -0.82804) (xy 0.11684 -0.85344) (xy 0.09144 -0.87376) (xy 0.0635 -0.889) (xy 0.03175 -0.89916)
					)
					(width 0)
					(fill yes)
				)
			)
		)
		(pad "145" smd custom
			(at 13.949934 -4.100068 180)
			(size 0.1143 0.1143)
			(layers "B.Cu" "B.Mask" "B.Paste")
			(net "M_B_DQ34")
			(options
				(clearance outline)
				(anchor circle)
			)
			(primitives
				(gr_poly
					(pts
						(xy 0 -0.9017) (xy -0.03175 -0.89916) (xy -0.0635 -0.889) (xy -0.09144 -0.87376) (xy -0.11684 -0.85344)
						(xy -0.13716 -0.82804) (xy -0.1524 -0.8001) (xy -0.16256 -0.76835) (xy -0.1651 -0.7366) (xy -0.1651 -0.44958)
						(xy -0.17272 -0.44196) (xy -0.19812 -0.4064) (xy -0.2032 -0.39624) (xy -0.20701 -0.38735) (xy -0.21209 -0.37719)
						(xy -0.2159 -0.36703) (xy -0.21844 -0.35687) (xy -0.22225 -0.34544) (xy -0.22352 -0.33528) (xy -0.22606 -0.32512)
						(xy -0.22733 -0.31369) (xy -0.22733 -0.30353) (xy -0.2286 -0.2921) (xy -0.22733 -0.28067) (xy -0.22733 -0.27051)
						(xy -0.22606 -0.25908) (xy -0.22352 -0.24892) (xy -0.22225 -0.23876) (xy -0.21844 -0.22733) (xy -0.2159 -0.21717)
						(xy -0.21209 -0.20701) (xy -0.20701 -0.19685) (xy -0.2032 -0.18796) (xy -0.19812 -0.1778) (xy -0.17272 -0.14224)
						(xy -0.1651 -0.13462) (xy -0.1651 0.7366) (xy -0.16256 0.76835) (xy -0.1524 0.8001) (xy -0.13716 0.82804)
						(xy -0.11684 0.85344) (xy -0.09144 0.87376) (xy -0.0635 0.889) (xy -0.03175 0.89916) (xy 0 0.9017)
						(xy 0.03175 0.89916) (xy 0.0635 0.889) (xy 0.09144 0.87376) (xy 0.11684 0.85344) (xy 0.13716 0.82804)
						(xy 0.1524 0.8001) (xy 0.16256 0.76835) (xy 0.1651 0.7366) (xy 0.1651 -0.13462) (xy 0.17272 -0.14224)
						(xy 0.19812 -0.1778) (xy 0.2032 -0.18796) (xy 0.20701 -0.19685) (xy 0.21209 -0.20701) (xy 0.2159 -0.21717)
						(xy 0.21844 -0.22733) (xy 0.22225 -0.23876) (xy 0.22352 -0.24892) (xy 0.22606 -0.25908) (xy 0.22733 -0.27051)
						(xy 0.22733 -0.28067) (xy 0.2286 -0.2921) (xy 0.22733 -0.30353) (xy 0.22733 -0.31369) (xy 0.22606 -0.32512)
						(xy 0.22352 -0.33528) (xy 0.22225 -0.34544) (xy 0.21844 -0.35687) (xy 0.2159 -0.36703) (xy 0.21209 -0.37719)
						(xy 0.20701 -0.38735) (xy 0.2032 -0.39624) (xy 0.19812 -0.4064) (xy 0.17272 -0.44196) (xy 0.1651 -0.44958)
						(xy 0.1651 -0.7366) (xy 0.16256 -0.76835) (xy 0.1524 -0.8001) (xy 0.13716 -0.82804) (xy 0.11684 -0.85344)
						(xy 0.09144 -0.87376) (xy 0.0635 -0.889) (xy 0.03175 -0.89916)
					)
					(width 0)
					(fill yes)
				)
			)
		)
		(pad "146" smd custom
			(at 14.249908 4.100068 180)
			(size 0.1143 0.1143)
			(layers "B.Cu" "B.Mask" "B.Paste")
			(net "GND")
			(options
				(clearance outline)
				(anchor circle)
			)
			(primitives
				(gr_poly
					(pts
						(xy 0 -0.9017) (xy -0.03175 -0.89916) (xy -0.0635 -0.889) (xy -0.09144 -0.87376) (xy -0.11684 -0.85344)
						(xy -0.13716 -0.82804) (xy -0.1524 -0.8001) (xy -0.16256 -0.76835) (xy -0.1651 -0.7366) (xy -0.1651 0.13462)
						(xy -0.17272 0.14224) (xy -0.19812 0.1778) (xy -0.2032 0.18796) (xy -0.20701 0.19685) (xy -0.21209 0.20701)
						(xy -0.2159 0.21717) (xy -0.21844 0.22733) (xy -0.22225 0.23876) (xy -0.22352 0.24892) (xy -0.22606 0.25908)
						(xy -0.22733 0.27051) (xy -0.22733 0.28067) (xy -0.2286 0.2921) (xy -0.22733 0.30353) (xy -0.22733 0.31369)
						(xy -0.22606 0.32512) (xy -0.22352 0.33528) (xy -0.22225 0.34544) (xy -0.21844 0.35687) (xy -0.2159 0.36703)
						(xy -0.21209 0.37719) (xy -0.20701 0.38735) (xy -0.2032 0.39624) (xy -0.19812 0.4064) (xy -0.17272 0.44196)
						(xy -0.1651 0.44958) (xy -0.1651 0.7366) (xy -0.16256 0.76835) (xy -0.1524 0.8001) (xy -0.13716 0.82804)
						(xy -0.11684 0.85344) (xy -0.09144 0.87376) (xy -0.0635 0.889) (xy -0.03175 0.89916) (xy 0 0.9017)
						(xy 0.03175 0.89916) (xy 0.0635 0.889) (xy 0.09144 0.87376) (xy 0.11684 0.85344) (xy 0.13716 0.82804)
						(xy 0.1524 0.8001) (xy 0.16256 0.76835) (xy 0.1651 0.7366) (xy 0.1651 0.44958) (xy 0.17272 0.44196)
						(xy 0.19812 0.4064) (xy 0.2032 0.39624) (xy 0.20701 0.38735) (xy 0.21209 0.37719) (xy 0.2159 0.36703)
						(xy 0.21844 0.35687) (xy 0.22225 0.34544) (xy 0.22352 0.33528) (xy 0.22606 0.32512) (xy 0.22733 0.31369)
						(xy 0.22733 0.30353) (xy 0.2286 0.2921) (xy 0.22733 0.28067) (xy 0.22733 0.27051) (xy 0.22606 0.25908)
						(xy 0.22352 0.24892) (xy 0.22225 0.23876) (xy 0.21844 0.22733) (xy 0.2159 0.21717) (xy 0.21209 0.20701)
						(xy 0.20701 0.19685) (xy 0.2032 0.18796) (xy 0.19812 0.1778) (xy 0.17272 0.14224) (xy 0.1651 0.13462)
						(xy 0.1651 -0.7366) (xy 0.16256 -0.76835) (xy 0.1524 -0.8001) (xy 0.13716 -0.82804) (xy 0.11684 -0.85344)
						(xy 0.09144 -0.87376) (xy 0.0635 -0.889) (xy 0.03175 -0.89916)
					)
					(width 0)
					(fill yes)
				)
			)
		)
	)
)
